# T6G (Grand Teton) — schematic netlist excerpt (pin names and nets, part order shuffled) for the footprints in the layout excerpt that follows; sources: Cadence DE-HDL packaged netlist, KiCad conversion of 04192023_DAF0TMB3IC0_F0TG_MB_C_brd_V02_OCP.brd

C2317  Q_CAP  1UF 25V 10% X6S  pkg C0402  page 176 : A = RST_USB_CPU0_HUB1_R_N ; B = GND
PR489  Q_RES  1.5 1% EMPTY  pkg 0402LF  page 222 : A = SW_PVDDIO_P1_SW2_RC ; B = GND

(kicad_pcb
	(version 20260206)
	(generator "pcbnew")
	(generator_version "10.0")
	(general
		(thickness 1.6)
		(legacy_teardrops no)
	)
	(paper "A4")
	(title_block
		(title "04192023_DAF0TMB3IC0_F0TG_MB_C_brd_V02_OCP.brd")
		(comment 1 "Grand Teton / footprints 4065-4066 of 8354")
	)
	(layers
		(0 "F.Cu" signal "TOP")
		(4 "In1.Cu" signal "GND")
		(6 "In2.Cu" signal "IN1")
		(8 "In3.Cu" signal "GND1")
		(10 "In4.Cu" signal "IN2")
		(12 "In5.Cu" signal "GND2")
		(14 "In6.Cu" signal "IN3")
		(16 "In7.Cu" signal "GND3")
		(18 "In8.Cu" signal "VCC")
		(20 "In9.Cu" signal "VCC1")
		(22 "In10.Cu" signal "GND4")
		(24 "In11.Cu" signal "IN4")
		(26 "In12.Cu" signal "GND5")
		(28 "In13.Cu" signal "IN5")
		(30 "In14.Cu" signal "GND6")
		(32 "In15.Cu" signal "IN6")
		(34 "In16.Cu" signal "GND7")
		(2 "B.Cu" signal "BOTTOM")
		(9 "F.Adhes" user "F.Adhesive")
		(11 "B.Adhes" user "B.Adhesive")
		(13 "F.Paste" user "Package Geometry/Pastemask Top")
		(15 "B.Paste" user "Package Geometry/Pastemask Bottom")
		(5 "F.SilkS" user "Ref Des/Silkscreen Top")
		(7 "B.SilkS" user "Ref Des/Silkscreen Bottom")
		(1 "F.Mask" user "Board Geometry/Soldermask Top")
		(3 "B.Mask" user "Board Geometry/Soldermask Bottom")
		(17 "Dwgs.User" user "User.Drawings")
		(19 "Cmts.User" user "User.Comments")
		(21 "Eco1.User" user "User.Eco1")
		(23 "Eco2.User" user "User.Eco2")
		(25 "Edge.Cuts" user "Board Geometry/Outline")
		(27 "Margin" user)
		(31 "F.CrtYd" user "Package Geometry/Place Bound Top")
		(29 "B.CrtYd" user "Package Geometry/Place Bound Bottom")
		(35 "F.Fab" user "Ref Des/Assembly Top")
		(33 "B.Fab" user "Ref Des/Assembly Bottom")
	)
	(footprint ""
		(layer "F.Cu")
		(at 124.633228 -51.185064 180)
		(property "Reference" "C2317"
			(at 0 0 180)
			(layer "F.SilkS")
			(hide yes)
			(effects
				(font
					(size 1.27 1.27)
				)
			)
		)
		(property "Value" ""
			(at 0 0 180)
			(layer "F.Fab")
			(effects
				(font
					(size 1.27 1.27)
				)
			)
		)
		(duplicate_pad_numbers_are_jumpers no)
		(fp_line
			(start 0.7874 0.4064)
			(end -0.7874 0.4064)
			(stroke
				(width 0.1524)
				(type default)
			)
			(layer "F.SilkS")
		)
		(fp_line
			(start 0.7874 -0.4064)
			(end 0.7874 0.4064)
			(stroke
				(width 0.1524)
				(type default)
			)
			(layer "F.SilkS")
		)
		(fp_line
			(start -0.7874 0.4064)
			(end -0.7874 -0.4064)
			(stroke
				(width 0.1524)
				(type default)
			)
			(layer "F.SilkS")
		)
		(fp_line
			(start -0.7874 -0.4064)
			(end 0.7874 -0.4064)
			(stroke
				(width 0.1524)
				(type default)
			)
			(layer "F.SilkS")
		)
		(fp_line
			(start 0.67945 0.3048)
			(end 0.120396 0.3048)
			(stroke
				(width 0.1)
				(type default)
			)
			(layer "F.Fab")
		)
		(fp_line
			(start 0.67945 -0.3048)
			(end 0.67945 0.3048)
			(stroke
				(width 0.1)
				(type default)
			)
			(layer "F.Fab")
		)
		(fp_line
			(start 0.12065 -0.2794)
			(end 0.12065 -0.3048)
			(stroke
				(width 0.1)
				(type default)
			)
			(layer "F.Fab")
		)
		(fp_line
			(start 0.12065 -0.3048)
			(end 0.67945 -0.3048)
			(stroke
				(width 0.1)
				(type default)
			)
			(layer "F.Fab")
		)
		(fp_line
			(start 0.120396 0.3048)
			(end 0.120396 0.2794)
			(stroke
				(width 0.1)
				(type default)
			)
			(layer "F.Fab")
		)
		(fp_line
			(start 0.120396 0.2794)
			(end -0.12065 0.2794)
			(stroke
				(width 0.1)
				(type default)
			)
			(layer "F.Fab")
		)
		(fp_line
			(start -0.12065 0.3048)
			(end -0.67945 0.3048)
			(stroke
				(width 0.1)
				(type default)
			)
			(layer "F.Fab")
		)
		(fp_line
			(start -0.12065 0.2794)
			(end -0.12065 0.3048)
			(stroke
				(width 0.1)
				(type default)
			)
			(layer "F.Fab")
		)
		(fp_line
			(start -0.12065 -0.2794)
			(end 0.12065 -0.2794)
			(stroke
				(width 0.1)
				(type default)
			)
			(layer "F.Fab")
		)
		(fp_line
			(start -0.12065 -0.305054)
			(end -0.12065 -0.2794)
			(stroke
				(width 0.1)
				(type default)
			)
			(layer "F.Fab")
		)
		(fp_line
			(start -0.67945 0.3048)
			(end -0.67945 -0.305054)
			(stroke
				(width 0.1)
				(type default)
			)
			(layer "F.Fab")
		)
		(fp_line
			(start -0.67945 -0.305054)
			(end -0.12065 -0.305054)
			(stroke
				(width 0.1)
				(type default)
			)
			(layer "F.Fab")
		)
		(pad "1" smd circle
			(at -0.40005 0 180)
			(size 0 0)
			(layers "F.Cu" "F.Mask" "F.Paste")
			(net "RST_USB_CPU0_HUB1_R_N")
		)
		(pad "2" smd circle
			(at 0.40005 0 180)
			(size 0 0)
			(layers "F.Cu" "F.Mask" "F.Paste")
			(net "GND")
		)
	)
	(footprint ""
		(layer "F.Cu")
		(at 41.509696 -344.986864 90)
		(property "Reference" "PR489"
			(at 0 0 90)
			(layer "F.SilkS")
			(hide yes)
			(effects
				(font
					(size 1.27 1.27)
				)
			)
		)
		(property "Value" ""
			(at 0 0 90)
			(layer "F.Fab")
			(effects
				(font
					(size 1.27 1.27)
				)
			)
		)
		(duplicate_pad_numbers_are_jumpers no)
		(fp_line
			(start 0.7874 -0.4064)
			(end 0.7874 0.4064)
			(stroke
				(width 0.1524)
				(type default)
			)
			(layer "F.SilkS")
		)
		(fp_line
			(start -0.7874 -0.4064)
			(end 0.7874 -0.4064)
			(stroke
				(width 0.1524)
				(type default)
			)
			(layer "F.SilkS")
		)
		(fp_line
			(start 0.7874 0.4064)
			(end -0.7874 0.4064)
			(stroke
				(width 0.1524)
				(type default)
			)
			(layer "F.SilkS")
		)
		(fp_line
			(start -0.7874 0.4064)
			(end -0.7874 -0.4064)
			(stroke
				(width 0.1524)
				(type default)
			)
			(layer "F.SilkS")
		)
		(fp_line
			(start -0.12065 -0.305054)
			(end -0.12065 -0.2794)
			(stroke
				(width 0.1)
				(type default)
			)
			(layer "F.Fab")
		)
		(fp_line
			(start -0.67945 -0.305054)
			(end -0.12065 -0.305054)
			(stroke
				(width 0.1)
				(type default)
			)
			(layer "F.Fab")
		)
		(fp_line
			(start 0.67945 -0.3048)
			(end 0.67945 0.3048)
			(stroke
				(width 0.1)
				(type default)
			)
			(layer "F.Fab")
		)
		(fp_line
			(start 0.12065 -0.3048)
			(end 0.67945 -0.3048)
			(stroke
				(width 0.1)
				(type default)
			)
			(layer "F.Fab")
		)
		(fp_line
			(start 0.12065 -0.2794)
			(end 0.12065 -0.3048)
			(stroke
				(width 0.1)
				(type default)
			)
			(layer "F.Fab")
		)
		(fp_line
			(start -0.12065 -0.2794)
			(end 0.12065 -0.2794)
			(stroke
				(width 0.1)
				(type default)
			)
			(layer "F.Fab")
		)
		(fp_line
			(start 0.120396 0.2794)
			(end -0.12065 0.2794)
			(stroke
				(width 0.1)
				(type default)
			)
			(layer "F.Fab")
		)
		(fp_line
			(start -0.12065 0.2794)
			(end -0.12065 0.3048)
			(stroke
				(width 0.1)
				(type default)
			)
			(layer "F.Fab")
		)
		(fp_line
			(start 0.67945 0.3048)
			(end 0.120396 0.3048)
			(stroke
				(width 0.1)
				(type default)
			)
			(layer "F.Fab")
		)
		(fp_line
			(start 0.120396 0.3048)
			(end 0.120396 0.2794)
			(stroke
				(width 0.1)
				(type default)
			)
			(layer "F.Fab")
		)
		(fp_line
			(start -0.12065 0.3048)
			(end -0.67945 0.3048)
			(stroke
				(width 0.1)
				(type default)
			)
			(layer "F.Fab")
		)
		(fp_line
			(start -0.67945 0.3048)
			(end -0.67945 -0.305054)
			(stroke
				(width 0.1)
				(type default)
			)
			(layer "F.Fab")
		)
		(pad "1" smd circle
			(at -0.40005 0 90)
			(size 0 0)
			(layers "F.Cu" "F.Mask" "F.Paste")
			(net "SW_PVDDIO_P1_SW2_RC")
		)
		(pad "2" smd circle
			(at 0.40005 0 90)
			(size 0 0)
			(layers "F.Cu" "F.Mask" "F.Paste")
			(net "GND")
		)
	)
)
